# S9S_MB_2U (Grand Teton) — schematic netlist excerpt (pin names and nets, part order shuffled) for the footprints in the layout excerpt that follows; sources: Cadence DE-HDL packaged netlist, KiCad conversion of 03242023_DA0F0TMBIJ0_F0T_Motherboard_J_brd_V01_OCP.brd

Q146  MOSFET_NCH_DUAL  PJT138K IC  pkg SOT363XD  page 146
  S1  = GND
  G1  = SWB_HSC_PWRGD
  D2  = SWB_HSC_PWRGD_ISO
  S2  = GND
  G2  = SWB_HSC_PWRGD_N
  D1  = SWB_HSC_PWRGD_N

R2934  Q_RES  4.7K 5% CHIP  pkg 0402LF  page 148 : A = P3V3_AUX ; B = FM_SWB_PWRGD_ISO

(kicad_pcb
	(version 20260206)
	(generator "pcbnew")
	(generator_version "10.0")
	(general
		(thickness 1.6)
		(legacy_teardrops no)
	)
	(paper "A4")
	(title_block
		(title "03242023_DA0F0TMBIJ0_F0T_Motherboard_J_brd_V01_OCP.brd")
		(comment 1 "Grand Teton / footprints 1246-1247 of 6105")
	)
	(layers
		(0 "F.Cu" signal "TOP")
		(4 "In1.Cu" signal "GND")
		(6 "In2.Cu" signal "IN1")
		(8 "In3.Cu" signal "GND1")
		(10 "In4.Cu" signal "IN2")
		(12 "In5.Cu" signal "GND2")
		(14 "In6.Cu" signal "IN3")
		(16 "In7.Cu" signal "GND3")
		(18 "In8.Cu" signal "VCC")
		(20 "In9.Cu" signal "VCC1")
		(22 "In10.Cu" signal "GND4")
		(24 "In11.Cu" signal "IN4")
		(26 "In12.Cu" signal "GND5")
		(28 "In13.Cu" signal "IN5")
		(30 "In14.Cu" signal "GND6")
		(32 "In15.Cu" signal "IN6")
		(34 "In16.Cu" signal "GND7")
		(2 "B.Cu" signal "BOTTOM")
		(9 "F.Adhes" user "F.Adhesive")
		(11 "B.Adhes" user "B.Adhesive")
		(13 "F.Paste" user "Package Geometry/Pastemask Top")
		(15 "B.Paste" user "Package Geometry/Pastemask Bottom")
		(5 "F.SilkS" user "Ref Des/Silkscreen Top")
		(7 "B.SilkS" user "Ref Des/Silkscreen Bottom")
		(1 "F.Mask" user "Board Geometry/Soldermask Top")
		(3 "B.Mask" user "Board Geometry/Soldermask Bottom")
		(17 "Dwgs.User" user "User.Drawings")
		(19 "Cmts.User" user "User.Comments")
		(21 "Eco1.User" user "User.Eco1")
		(23 "Eco2.User" user "User.Eco2")
		(25 "Edge.Cuts" user "Board Geometry/Outline")
		(27 "Margin" user)
		(31 "F.CrtYd" user "Package Geometry/Place Bound Top")
		(29 "B.CrtYd" user "Package Geometry/Place Bound Bottom")
		(35 "F.Fab" user "Ref Des/Assembly Top")
		(33 "B.Fab" user "Ref Des/Assembly Bottom")
	)
	(footprint ""
		(layer "F.Cu")
		(at 360.553 -415.889948)
		(property "Reference" "Q146"
			(at -1.4224 -1.768348 0)
			(unlocked yes)
			(layer "F.SilkS")
			(effects
				(font
					(size 0.7874 0.5842)
					(thickness 0.1524)
				)
				(justify left)
			)
		)
		(property "Value" ""
			(at 0 0 0)
			(layer "F.Fab")
			(effects
				(font
					(size 1.27 1.27)
				)
			)
		)
		(duplicate_pad_numbers_are_jumpers no)
		(fp_line
			(start -1.332738 -1.100074)
			(end -0.4826 -1.100074)
			(stroke
				(width 0.1524)
				(type default)
			)
			(layer "F.SilkS")
		)
		(fp_line
			(start -1.332738 1.100074)
			(end -1.332738 -1.100074)
			(stroke
				(width 0.1524)
				(type default)
			)
			(layer "F.SilkS")
		)
		(fp_line
			(start -0.4826 -1.100074)
			(end 0 -0.541274)
			(stroke
				(width 0.1524)
				(type default)
			)
			(layer "F.SilkS")
		)
		(fp_line
			(start 0 -0.541274)
			(end 0.4826 -1.100074)
			(stroke
				(width 0.1524)
				(type default)
			)
			(layer "F.SilkS")
		)
		(fp_line
			(start 0.4826 -1.100074)
			(end 1.332738 -1.100074)
			(stroke
				(width 0.1524)
				(type default)
			)
			(layer "F.SilkS")
		)
		(fp_line
			(start 1.332738 -1.100074)
			(end 1.332738 1.100074)
			(stroke
				(width 0.1524)
				(type default)
			)
			(layer "F.SilkS")
		)
		(fp_line
			(start 1.332738 1.100074)
			(end -1.332738 1.100074)
			(stroke
				(width 0.1524)
				(type default)
			)
			(layer "F.SilkS")
		)
		(fp_poly
			(pts
				(xy -2.2352 -0.298958) (xy -2.2352 -1.001014) (xy -1.533144 -0.649986)
			)
			(stroke
				(width 0)
				(type default)
			)
			(fill yes)
			(layer "F.SilkS")
		)
		(fp_line
			(start -0.674878 -1.100074)
			(end 0.674878 -1.100074)
			(stroke
				(width 0.1)
				(type default)
			)
			(layer "F.Fab")
		)
		(fp_line
			(start -0.674878 1.100074)
			(end -0.674878 -1.100074)
			(stroke
				(width 0.1)
				(type default)
			)
			(layer "F.Fab")
		)
		(fp_line
			(start 0.674878 -1.100074)
			(end 0.674878 1.100074)
			(stroke
				(width 0.1)
				(type default)
			)
			(layer "F.Fab")
		)
		(fp_line
			(start 0.674878 1.100074)
			(end -0.674878 1.100074)
			(stroke
				(width 0.1)
				(type default)
			)
			(layer "F.Fab")
		)
		(fp_poly
			(pts
				(xy -2.2352 -0.298958) (xy -2.2352 -1.001014) (xy -1.533144 -0.649986)
			)
			(stroke
				(width 0)
				(type default)
			)
			(fill yes)
			(layer "F.Fab")
		)
		(pad "1" smd rect
			(at -0.94996 -0.649986 90)
			(size 0.4318 0.508)
			(layers "F.Cu" "F.Mask" "F.Paste")
			(net "GND")
		)
		(pad "2" smd rect
			(at -0.94996 0 90)
			(size 0.4318 0.508)
			(layers "F.Cu" "F.Mask" "F.Paste")
			(net "SWB_HSC_PWRGD")
		)
		(pad "3" smd rect
			(at -0.94996 0.649986 90)
			(size 0.4318 0.508)
			(layers "F.Cu" "F.Mask" "F.Paste")
			(net "SWB_HSC_PWRGD_ISO")
		)
		(pad "4" smd rect
			(at 0.94996 0.649986 90)
			(size 0.4318 0.508)
			(layers "F.Cu" "F.Mask" "F.Paste")
			(net "GND")
		)
		(pad "5" smd rect
			(at 0.94996 0 90)
			(size 0.4318 0.508)
			(layers "F.Cu" "F.Mask" "F.Paste")
			(net "SWB_HSC_PWRGD_N")
		)
		(pad "6" smd rect
			(at 0.94996 -0.649986 90)
			(size 0.4318 0.508)
			(layers "F.Cu" "F.Mask" "F.Paste")
			(net "SWB_HSC_PWRGD_N")
		)
	)
	(footprint ""
		(layer "F.Cu")
		(at 424.204892 -385.282948)
		(property "Reference" "R2934"
			(at 0 0 0)
			(layer "F.SilkS")
			(hide yes)
			(effects
				(font
					(size 1.27 1.27)
				)
			)
		)
		(property "Value" ""
			(at 0 0 0)
			(layer "F.Fab")
			(effects
				(font
					(size 1.27 1.27)
				)
			)
		)
		(duplicate_pad_numbers_are_jumpers no)
		(fp_line
			(start -0.7874 -0.4064)
			(end 0.7874 -0.4064)
			(stroke
				(width 0.1524)
				(type default)
			)
			(layer "F.SilkS")
		)
		(fp_line
			(start -0.7874 0.4064)
			(end -0.7874 -0.4064)
			(stroke
				(width 0.1524)
				(type default)
			)
			(layer "F.SilkS")
		)
		(fp_line
			(start 0.7874 -0.4064)
			(end 0.7874 0.4064)
			(stroke
				(width 0.1524)
				(type default)
			)
			(layer "F.SilkS")
		)
		(fp_line
			(start 0.7874 0.4064)
			(end -0.7874 0.4064)
			(stroke
				(width 0.1524)
				(type default)
			)
			(layer "F.SilkS")
		)
		(fp_line
			(start -0.67945 -0.305054)
			(end -0.12065 -0.305054)
			(stroke
				(width 0.1)
				(type default)
			)
			(layer "F.Fab")
		)
		(fp_line
			(start -0.67945 0.3048)
			(end -0.67945 -0.305054)
			(stroke
				(width 0.1)
				(type default)
			)
			(layer "F.Fab")
		)
		(fp_line
			(start -0.12065 -0.305054)
			(end -0.12065 -0.2794)
			(stroke
				(width 0.1)
				(type default)
			)
			(layer "F.Fab")
		)
		(fp_line
			(start -0.12065 -0.2794)
			(end 0.12065 -0.2794)
			(stroke
				(width 0.1)
				(type default)
			)
			(layer "F.Fab")
		)
		(fp_line
			(start -0.12065 0.2794)
			(end -0.12065 0.3048)
			(stroke
				(width 0.1)
				(type default)
			)
			(layer "F.Fab")
		)
		(fp_line
			(start -0.12065 0.3048)
			(end -0.67945 0.3048)
			(stroke
				(width 0.1)
				(type default)
			)
			(layer "F.Fab")
		)
		(fp_line
			(start 0.120396 0.2794)
			(end -0.12065 0.2794)
			(stroke
				(width 0.1)
				(type default)
			)
			(layer "F.Fab")
		)
		(fp_line
			(start 0.120396 0.3048)
			(end 0.120396 0.2794)
			(stroke
				(width 0.1)
				(type default)
			)
			(layer "F.Fab")
		)
		(fp_line
			(start 0.12065 -0.3048)
			(end 0.67945 -0.3048)
			(stroke
				(width 0.1)
				(type default)
			)
			(layer "F.Fab")
		)
		(fp_line
			(start 0.12065 -0.2794)
			(end 0.12065 -0.3048)
			(stroke
				(width 0.1)
				(type default)
			)
			(layer "F.Fab")
		)
		(fp_line
			(start 0.67945 -0.3048)
			(end 0.67945 0.3048)
			(stroke
				(width 0.1)
				(type default)
			)
			(layer "F.Fab")
		)
		(fp_line
			(start 0.67945 0.3048)
			(end 0.120396 0.3048)
			(stroke
				(width 0.1)
				(type default)
			)
			(layer "F.Fab")
		)
		(pad "1" smd circle
			(at -0.40005 0)
			(size 0 0)
			(layers "F.Cu" "F.Mask" "F.Paste")
			(net "P3V3_AUX")
		)
		(pad "2" smd circle
			(at 0.40005 0)
			(size 0 0)
			(layers "F.Cu" "F.Mask" "F.Paste")
			(net "FM_SWB_PWRGD_ISO")
		)
	)
)
